(kicad_pcb
	(version 20260206)
	(generator "pcbnew")
	(generator_version "10.0")
	(general
		(thickness 1.6)
		(legacy_teardrops no)
	)
	(paper "A4")
	(title_block
		(title "fcb — 12433-1M.1206WZS1330.brd")
		(comment 1 "Open Vault / Knox (Wiwynn) / footprints 491-495 of 495")
	)
	(layers
		(0 "F.Cu" signal "TOP")
		(4 "In1.Cu" signal "L2GND")
		(6 "In2.Cu" signal "L3VCC")
		(2 "B.Cu" signal "BOTTOM")
		(9 "F.Adhes" user "F.Adhesive")
		(11 "B.Adhes" user "B.Adhesive")
		(13 "F.Paste" user "Package Geometry/Pastemask Top")
		(15 "B.Paste" user "Package Geometry/Pastemask Bottom")
		(5 "F.SilkS" user "Ref Des/Silkscreen Top")
		(7 "B.SilkS" user "Ref Des/Silkscreen Bottom")
		(1 "F.Mask" user "Board Geometry/Soldermask Top")
		(3 "B.Mask" user "Board Geometry/Soldermask Bottom")
		(17 "Dwgs.User" user "User.Drawings")
		(19 "Cmts.User" user "User.Comments")
		(21 "Eco1.User" user "User.Eco1")
		(23 "Eco2.User" user "User.Eco2")
		(25 "Edge.Cuts" user "Board Geometry/Outline")
		(27 "Margin" user)
		(31 "F.CrtYd" user "Package Geometry/Place Bound Top")
		(29 "B.CrtYd" user "Package Geometry/Place Bound Bottom")
		(35 "F.Fab" user "Ref Des/Assembly Top")
		(33 "B.Fab" user "Ref Des/Assembly Bottom")
	)
	(footprint ""
		(layer "B.Cu")
		(at 45.449998 -337.49996 90)
		(property "Reference" "H13"
			(at 0 0 90)
			(layer "B.SilkS")
			(hide yes)
			(effects
				(font
					(size 1.27 1.27)
				)
				(justify mirror)
			)
		)
		(property "Value" "STF375R199H50-GP"
			(at 6.124702 -0.033274 90)
			(unlocked yes)
			(layer "B.Fab")
			(hide yes)
			(effects
				(font
					(size 1.016 1.016)
					(thickness 0.1524)
				)
				(justify mirror)
			)
		)
		(property "Device Type" "STF375R199H50"
			(at 6.124702 -1.557274 90)
			(unlocked yes)
			(layer "B.Fab")
			(hide yes)
			(effects
				(font
					(size 1.016 1.016)
					(thickness 0.1524)
				)
				(justify mirror)
			)
		)
		(duplicate_pad_numbers_are_jumpers no)
		(fp_circle
			(center 0 0)
			(end 0 5.1181)
			(stroke
				(width 0.3048)
				(type default)
			)
			(fill no)
			(layer "B.SilkS")
		)
		(fp_poly
			(pts
				(arc
					(start -4.0005 0)
					(mid 4.0005 0)
					(end -4.0005 0)
				)
			)
			(stroke
				(width 0)
				(type default)
			)
			(fill no)
			(layer "B.CrtYd")
		)
		(fp_poly
			(pts
				(arc
					(start -5.2705 0.00254)
					(mid 5.270501 0)
					(end -5.2705 -0.00254)
				)
				(arc
					(start -4.0005 -0.00254)
					(mid 4.000501 0)
					(end -4.0005 0.00254)
				)
			)
			(stroke
				(width 0)
				(type default)
			)
			(fill no)
			(layer "B.CrtYd")
		)
		(fp_poly
			(pts
				(arc
					(start -5.2705 0)
					(mid 5.2705 0)
					(end -5.2705 0)
				)
			)
			(stroke
				(width 0)
				(type default)
			)
			(fill no)
			(layer "F.CrtYd")
		)
		(fp_poly
			(pts
				(arc
					(start -5.2705 0)
					(mid 5.2705 0)
					(end -5.2705 0)
				)
			)
			(stroke
				(width 0)
				(type default)
			)
			(fill no)
			(layer "B.Fab")
		)
		(fp_poly
			(pts
				(arc
					(start -5.2705 0)
					(mid 5.2705 0)
					(end -5.2705 0)
				)
			)
			(stroke
				(width 0)
				(type default)
			)
			(fill no)
			(layer "F.Fab")
		)
		(pad "1" thru_hole circle
			(at 0 0 270)
			(size 9.525 9.525)
			(drill 5.0546)
			(layers "*.Cu" "*.Mask")
			(remove_unused_layers no)
			(net "GND")
			(clearance -1.7272)
			(padstack
				(mode front_inner_back)
				(layer "Inner"
					(shape circle)
					(size 5.461 5.461)
					(clearance 0.3048)
				)
				(layer "B.Cu"
					(shape circle)
					(size 9.525 9.525)
					(thermal_gap 0.3048)
					(clearance -1.7272)
				)
			)
		)
	)
	(footprint ""
		(layer "B.Cu")
		(at 40.999918 -463.049874 90)
		(property "Reference" "H11"
			(at 0 0 90)
			(layer "B.SilkS")
			(hide yes)
			(effects
				(font
					(size 1.27 1.27)
				)
				(justify mirror)
			)
		)
		(property "Value" "STF375R199H50-GP"
			(at 6.124702 -0.033274 90)
			(unlocked yes)
			(layer "B.Fab")
			(hide yes)
			(effects
				(font
					(size 1.016 1.016)
					(thickness 0.1524)
				)
				(justify mirror)
			)
		)
		(property "Device Type" "STF375R199H50"
			(at 6.124702 -1.557274 90)
			(unlocked yes)
			(layer "B.Fab")
			(hide yes)
			(effects
				(font
					(size 1.016 1.016)
					(thickness 0.1524)
				)
				(justify mirror)
			)
		)
		(duplicate_pad_numbers_are_jumpers no)
		(fp_circle
			(center 0 0)
			(end 0 5.1181)
			(stroke
				(width 0.3048)
				(type default)
			)
			(fill no)
			(layer "B.SilkS")
		)
		(fp_poly
			(pts
				(arc
					(start 0 4.0005)
					(mid 0 -4.0005)
					(end 0 4.0005)
				)
			)
			(stroke
				(width 0)
				(type default)
			)
			(fill no)
			(layer "B.CrtYd")
		)
		(fp_poly
			(pts
				(arc
					(start -5.2705 0.00254)
					(mid 5.270501 0)
					(end -5.2705 -0.00254)
				)
				(arc
					(start -4.0005 -0.00254)
					(mid 4.000501 0)
					(end -4.0005 0.00254)
				)
			)
			(stroke
				(width 0)
				(type default)
			)
			(fill no)
			(layer "B.CrtYd")
		)
		(fp_poly
			(pts
				(arc
					(start 0 5.2705)
					(mid 0 -5.2705)
					(end 0 5.2705)
				)
			)
			(stroke
				(width 0)
				(type default)
			)
			(fill no)
			(layer "F.CrtYd")
		)
		(fp_poly
			(pts
				(arc
					(start 0 5.2705)
					(mid 0 -5.2705)
					(end 0 5.2705)
				)
			)
			(stroke
				(width 0)
				(type default)
			)
			(fill no)
			(layer "B.Fab")
		)
		(fp_poly
			(pts
				(arc
					(start 0 5.2705)
					(mid 0 -5.2705)
					(end 0 5.2705)
				)
			)
			(stroke
				(width 0)
				(type default)
			)
			(fill no)
			(layer "F.Fab")
		)
		(pad "1" thru_hole circle
			(at 0 0 270)
			(size 9.525 9.525)
			(drill 5.0546)
			(layers "*.Cu" "*.Mask")
			(remove_unused_layers no)
			(net "GND")
			(clearance -1.7272)
			(padstack
				(mode front_inner_back)
				(layer "Inner"
					(shape circle)
					(size 5.461 5.461)
					(clearance 0.3048)
				)
				(layer "B.Cu"
					(shape circle)
					(size 9.525 9.525)
					(thermal_gap 0.3048)
					(clearance -1.7272)
				)
			)
		)
	)
	(footprint ""
		(layer "B.Cu")
		(at 24.500078 -443.95009 90)
		(property "Reference" "H10"
			(at 0 0 90)
			(layer "B.SilkS")
			(hide yes)
			(effects
				(font
					(size 1.27 1.27)
				)
				(justify mirror)
			)
		)
		(property "Value" "STF375R199H50-GP"
			(at 6.124702 -0.033274 90)
			(unlocked yes)
			(layer "B.Fab")
			(hide yes)
			(effects
				(font
					(size 1.016 1.016)
					(thickness 0.1524)
				)
				(justify mirror)
			)
		)
		(property "Device Type" "STF375R199H50"
			(at 6.124702 -1.557274 90)
			(unlocked yes)
			(layer "B.Fab")
			(hide yes)
			(effects
				(font
					(size 1.016 1.016)
					(thickness 0.1524)
				)
				(justify mirror)
			)
		)
		(duplicate_pad_numbers_are_jumpers no)
		(fp_circle
			(center 0 0)
			(end 0 5.1181)
			(stroke
				(width 0.3048)
				(type default)
			)
			(fill no)
			(layer "B.SilkS")
		)
		(fp_poly
			(pts
				(arc
					(start 0 4.0005)
					(mid 0 -4.0005)
					(end 0 4.0005)
				)
			)
			(stroke
				(width 0)
				(type default)
			)
			(fill no)
			(layer "B.CrtYd")
		)
		(fp_poly
			(pts
				(arc
					(start -5.2705 0.00254)
					(mid 5.270501 0)
					(end -5.2705 -0.00254)
				)
				(arc
					(start -4.0005 -0.00254)
					(mid 4.000501 0)
					(end -4.0005 0.00254)
				)
			)
			(stroke
				(width 0)
				(type default)
			)
			(fill no)
			(layer "B.CrtYd")
		)
		(fp_poly
			(pts
				(arc
					(start 0 5.2705)
					(mid 0 -5.2705)
					(end 0 5.2705)
				)
			)
			(stroke
				(width 0)
				(type default)
			)
			(fill no)
			(layer "F.CrtYd")
		)
		(fp_poly
			(pts
				(arc
					(start 0 5.2705)
					(mid 0 -5.2705)
					(end 0 5.2705)
				)
			)
			(stroke
				(width 0)
				(type default)
			)
			(fill no)
			(layer "B.Fab")
		)
		(fp_poly
			(pts
				(arc
					(start 0 5.2705)
					(mid 0 -5.2705)
					(end 0 5.2705)
				)
			)
			(stroke
				(width 0)
				(type default)
			)
			(fill no)
			(layer "F.Fab")
		)
		(pad "1" thru_hole circle
			(at 0 0 270)
			(size 9.525 9.525)
			(drill 5.0546)
			(layers "*.Cu" "*.Mask")
			(remove_unused_layers no)
			(net "P12V_AUX")
			(clearance -1.7272)
			(padstack
				(mode front_inner_back)
				(layer "Inner"
					(shape circle)
					(size 5.461 5.461)
					(clearance 0.3048)
				)
				(layer "B.Cu"
					(shape circle)
					(size 9.525 9.525)
					(thermal_gap 0.3048)
					(clearance -1.7272)
				)
			)
		)
	)
	(footprint ""
		(layer "B.Cu")
		(at 40.999918 -443.95009 90)
		(property "Reference" "H12"
			(at 0 0 90)
			(layer "B.SilkS")
			(hide yes)
			(effects
				(font
					(size 1.27 1.27)
				)
				(justify mirror)
			)
		)
		(property "Value" "STF375R199H50-GP"
			(at 6.124702 -0.033274 90)
			(unlocked yes)
			(layer "B.Fab")
			(hide yes)
			(effects
				(font
					(size 1.016 1.016)
					(thickness 0.1524)
				)
				(justify mirror)
			)
		)
		(property "Device Type" "STF375R199H50"
			(at 6.124702 -1.557274 90)
			(unlocked yes)
			(layer "B.Fab")
			(hide yes)
			(effects
				(font
					(size 1.016 1.016)
					(thickness 0.1524)
				)
				(justify mirror)
			)
		)
		(duplicate_pad_numbers_are_jumpers no)
		(fp_circle
			(center 0 0)
			(end 0 5.1181)
			(stroke
				(width 0.3048)
				(type default)
			)
			(fill no)
			(layer "B.SilkS")
		)
		(fp_poly
			(pts
				(arc
					(start 0 4.0005)
					(mid 0 -4.0005)
					(end 0 4.0005)
				)
			)
			(stroke
				(width 0)
				(type default)
			)
			(fill no)
			(layer "B.CrtYd")
		)
		(fp_poly
			(pts
				(arc
					(start -5.2705 0.00254)
					(mid 5.270501 0)
					(end -5.2705 -0.00254)
				)
				(arc
					(start -4.0005 -0.00254)
					(mid 4.000501 0)
					(end -4.0005 0.00254)
				)
			)
			(stroke
				(width 0)
				(type default)
			)
			(fill no)
			(layer "B.CrtYd")
		)
		(fp_poly
			(pts
				(arc
					(start 0 5.2705)
					(mid 0 -5.2705)
					(end 0 5.2705)
				)
			)
			(stroke
				(width 0)
				(type default)
			)
			(fill no)
			(layer "F.CrtYd")
		)
		(fp_poly
			(pts
				(arc
					(start 0 5.2705)
					(mid 0 -5.2705)
					(end 0 5.2705)
				)
			)
			(stroke
				(width 0)
				(type default)
			)
			(fill no)
			(layer "B.Fab")
		)
		(fp_poly
			(pts
				(arc
					(start 0 5.2705)
					(mid 0 -5.2705)
					(end 0 5.2705)
				)
			)
			(stroke
				(width 0)
				(type default)
			)
			(fill no)
			(layer "F.Fab")
		)
		(pad "1" thru_hole circle
			(at 0 0 270)
			(size 9.525 9.525)
			(drill 5.0546)
			(layers "*.Cu" "*.Mask")
			(remove_unused_layers no)
			(net "GND")
			(clearance -1.7272)
			(padstack
				(mode front_inner_back)
				(layer "Inner"
					(shape circle)
					(size 5.461 5.461)
					(clearance 0.3048)
				)
				(layer "B.Cu"
					(shape circle)
					(size 9.525 9.525)
					(thermal_gap 0.3048)
					(clearance -1.7272)
				)
			)
		)
	)
	(footprint ""
		(layer "B.Cu")
		(at 24.500078 -463.049874 90)
		(property "Reference" "H9"
			(at 0 0 90)
			(layer "B.SilkS")
			(hide yes)
			(effects
				(font
					(size 1.27 1.27)
				)
				(justify mirror)
			)
		)
		(property "Value" "STF375R199H50-GP"
			(at 6.124702 -0.033274 90)
			(unlocked yes)
			(layer "B.Fab")
			(hide yes)
			(effects
				(font
					(size 1.016 1.016)
					(thickness 0.1524)
				)
				(justify mirror)
			)
		)
		(property "Device Type" "STF375R199H50"
			(at 6.124702 -1.557274 90)
			(unlocked yes)
			(layer "B.Fab")
			(hide yes)
			(effects
				(font
					(size 1.016 1.016)
					(thickness 0.1524)
				)
				(justify mirror)
			)
		)
		(duplicate_pad_numbers_are_jumpers no)
		(fp_circle
			(center 0 0)
			(end 0 5.1181)
			(stroke
				(width 0.3048)
				(type default)
			)
			(fill no)
			(layer "B.SilkS")
		)
		(fp_poly
			(pts
				(arc
					(start 0 4.0005)
					(mid 0 -4.0005)
					(end 0 4.0005)
				)
			)
			(stroke
				(width 0)
				(type default)
			)
			(fill no)
			(layer "B.CrtYd")
		)
		(fp_poly
			(pts
				(arc
					(start -5.2705 0.00254)
					(mid 5.270501 0)
					(end -5.2705 -0.00254)
				)
				(arc
					(start -4.0005 -0.00254)
					(mid 4.000501 0)
					(end -4.0005 0.00254)
				)
			)
			(stroke
				(width 0)
				(type default)
			)
			(fill no)
			(layer "B.CrtYd")
		)
		(fp_poly
			(pts
				(arc
					(start 0 5.2705)
					(mid 0 -5.2705)
					(end 0 5.2705)
				)
			)
			(stroke
				(width 0)
				(type default)
			)
			(fill no)
			(layer "F.CrtYd")
		)
		(fp_poly
			(pts
				(arc
					(start 0 5.2705)
					(mid 0 -5.2705)
					(end 0 5.2705)
				)
			)
			(stroke
				(width 0)
				(type default)
			)
			(fill no)
			(layer "B.Fab")
		)
		(fp_poly
			(pts
				(arc
					(start 0 5.2705)
					(mid 0 -5.2705)
					(end 0 5.2705)
				)
			)
			(stroke
				(width 0)
				(type default)
			)
			(fill no)
			(layer "F.Fab")
		)
		(pad "1" thru_hole circle
			(at 0 0 270)
			(size 9.525 9.525)
			(drill 5.0546)
			(layers "*.Cu" "*.Mask")
			(remove_unused_layers no)
			(net "P12V_AUX")
			(clearance -1.7272)
			(padstack
				(mode front_inner_back)
				(layer "Inner"
					(shape circle)
					(size 5.461 5.461)
					(clearance 0.3048)
				)
				(layer "B.Cu"
					(shape circle)
					(size 9.525 9.525)
					(thermal_gap 0.3048)
					(clearance -1.7272)
				)
			)
		)
	)
)
